# SCM (Grand Teton) — schematic netlist excerpt (pin names and nets, part order shuffled) for the footprints in the layout excerpt that follows; sources: Cadence DE-HDL packaged netlist, KiCad conversion of 12092022_DA0F0TMDCD0_F0T_Management_Board_D_brd_V3_OCP.brd

R159  Q_RES  33.2 1% CHIP  pkg 0402LF  page 13 : A = FM_JTAG_TCK_MUX_BMC_SEL ; B = FM_JTAG_TCK_MUX_BMC_SEL_R1
C141  Q_CAP  0.1UF 25V 10% X7R  pkg 0402  page 41 : A = VCCIO1 ; B = GND

(kicad_pcb
	(version 20260206)
	(generator "pcbnew")
	(generator_version "10.0")
	(general
		(thickness 1.6)
		(legacy_teardrops no)
	)
	(paper "A4")
	(title_block
		(title "12092022_DA0F0TMDCD0_F0T_Management_Board_D_brd_V3_OCP.brd")
		(comment 1 "Grand Teton / footprints 1310-1311 of 1440")
	)
	(layers
		(0 "F.Cu" signal "TOP")
		(4 "In1.Cu" signal "GND")
		(6 "In2.Cu" signal "IN1")
		(8 "In3.Cu" signal "GND1")
		(10 "In4.Cu" signal "IN2")
		(12 "In5.Cu" signal "VCC")
		(14 "In6.Cu" signal "VCC1")
		(16 "In7.Cu" signal "IN3")
		(18 "In8.Cu" signal "GND2")
		(20 "In9.Cu" signal "IN4")
		(22 "In10.Cu" signal "GND3")
		(2 "B.Cu" signal "BOTTOM")
		(9 "F.Adhes" user "F.Adhesive")
		(11 "B.Adhes" user "B.Adhesive")
		(13 "F.Paste" user "Package Geometry/Pastemask Top")
		(15 "B.Paste" user "Package Geometry/Pastemask Bottom")
		(5 "F.SilkS" user "Ref Des/Silkscreen Top")
		(7 "B.SilkS" user "Ref Des/Silkscreen Bottom")
		(1 "F.Mask" user "Board Geometry/Soldermask Top")
		(3 "B.Mask" user "Board Geometry/Soldermask Bottom")
		(17 "Dwgs.User" user "User.Drawings")
		(19 "Cmts.User" user "User.Comments")
		(21 "Eco1.User" user "User.Eco1")
		(23 "Eco2.User" user "User.Eco2")
		(25 "Edge.Cuts" user "Board Geometry/Outline")
		(27 "Margin" user)
		(31 "F.CrtYd" user "Package Geometry/Place Bound Top")
		(29 "B.CrtYd" user "Package Geometry/Place Bound Bottom")
		(35 "F.Fab" user "Ref Des/Assembly Top")
		(33 "B.Fab" user "Ref Des/Assembly Bottom")
	)
	(footprint ""
		(layer "B.Cu")
		(at 18.259298 -94.786958 180)
		(property "Reference" "C141"
			(at 0 0 0)
			(layer "B.SilkS")
			(hide yes)
			(effects
				(font
					(size 1.27 1.27)
				)
				(justify mirror)
			)
		)
		(property "Value" ""
			(at 0 0 0)
			(layer "B.Fab")
			(effects
				(font
					(size 1.27 1.27)
				)
				(justify mirror)
			)
		)
		(duplicate_pad_numbers_are_jumpers no)
		(fp_line
			(start 0.69215 0.2921)
			(end 0.69215 -0.2921)
			(stroke
				(width 0.1524)
				(type default)
			)
			(layer "B.SilkS")
		)
		(fp_line
			(start 0.69215 -0.2921)
			(end -0.69215 -0.2921)
			(stroke
				(width 0.1524)
				(type default)
			)
			(layer "B.SilkS")
		)
		(fp_line
			(start -0.69215 0.2921)
			(end 0.69215 0.2921)
			(stroke
				(width 0.1524)
				(type default)
			)
			(layer "B.SilkS")
		)
		(fp_line
			(start -0.69215 -0.2921)
			(end -0.69215 0.2921)
			(stroke
				(width 0.1524)
				(type default)
			)
			(layer "B.SilkS")
		)
		(fp_line
			(start 0.51435 0.2794)
			(end 0.51435 -0.2794)
			(stroke
				(width 0.1)
				(type default)
			)
			(layer "B.Fab")
		)
		(fp_line
			(start 0.51435 -0.2794)
			(end -0.51435 -0.2794)
			(stroke
				(width 0.1)
				(type default)
			)
			(layer "B.Fab")
		)
		(fp_line
			(start -0.51435 0.2794)
			(end 0.51435 0.2794)
			(stroke
				(width 0.1)
				(type default)
			)
			(layer "B.Fab")
		)
		(fp_line
			(start -0.51435 -0.2794)
			(end -0.51435 0.2794)
			(stroke
				(width 0.1)
				(type default)
			)
			(layer "B.Fab")
		)
		(pad "1" smd circle
			(at 0.40005 0)
			(size 0 0)
			(layers "B.Cu" "B.Mask" "B.Paste")
			(net "VCCIO1")
		)
		(pad "2" smd circle
			(at -0.40005 0)
			(size 0 0)
			(layers "B.Cu" "B.Mask" "B.Paste")
			(net "GND")
		)
		(zone
			(layer "B.Cu")
			(hatch none 0.5)
			(connect_pads
				(clearance 0)
			)
			(min_thickness 0.25)
			(keepout
				(tracks not_allowed)
				(vias allowed)
				(pads allowed)
				(copperpour not_allowed)
				(footprints allowed)
			)
			(placement
				(enabled no)
				(sheetname "")
			)
			(fill
				(thermal_gap 0.5)
				(thermal_bridge_width 0.5)
				(island_removal_mode 0)
			)
			(polygon
				(pts
					(xy 18.068798 -94.874588) (xy 18.160238 -94.932754) (xy 18.359628 -94.932754) (xy 18.449798 -94.874588)
					(xy 18.449798 -94.699328) (xy 18.359628 -94.640908) (xy 18.160238 -94.640908) (xy 18.068798 -94.699074)
				)
			)
		)
	)
	(footprint ""
		(layer "B.Cu")
		(at 35.433 -36.195 -90)
		(property "Reference" "R159"
			(at 0 0 90)
			(layer "B.SilkS")
			(hide yes)
			(effects
				(font
					(size 1.27 1.27)
				)
				(justify mirror)
			)
		)
		(property "Value" ""
			(at 0 0 90)
			(layer "B.Fab")
			(effects
				(font
					(size 1.27 1.27)
				)
				(justify mirror)
			)
		)
		(duplicate_pad_numbers_are_jumpers no)
		(fp_line
			(start -0.7874 0.4064)
			(end 0.7874 0.4064)
			(stroke
				(width 0.1524)
				(type default)
			)
			(layer "B.SilkS")
		)
		(fp_line
			(start 0.7874 0.4064)
			(end 0.7874 -0.4064)
			(stroke
				(width 0.1524)
				(type default)
			)
			(layer "B.SilkS")
		)
		(fp_line
			(start -0.7874 -0.4064)
			(end -0.7874 0.4064)
			(stroke
				(width 0.1524)
				(type default)
			)
			(layer "B.SilkS")
		)
		(fp_line
			(start 0.7874 -0.4064)
			(end -0.7874 -0.4064)
			(stroke
				(width 0.1524)
				(type default)
			)
			(layer "B.SilkS")
		)
		(fp_line
			(start -0.67945 0.3048)
			(end -0.120396 0.3048)
			(stroke
				(width 0.1)
				(type default)
			)
			(layer "B.Fab")
		)
		(fp_line
			(start -0.120396 0.3048)
			(end -0.120396 0.2794)
			(stroke
				(width 0.1)
				(type default)
			)
			(layer "B.Fab")
		)
		(fp_line
			(start 0.12065 0.3048)
			(end 0.67945 0.3048)
			(stroke
				(width 0.1)
				(type default)
			)
			(layer "B.Fab")
		)
		(fp_line
			(start 0.67945 0.3048)
			(end 0.67945 -0.305054)
			(stroke
				(width 0.1)
				(type default)
			)
			(layer "B.Fab")
		)
		(fp_line
			(start -0.120396 0.2794)
			(end 0.12065 0.2794)
			(stroke
				(width 0.1)
				(type default)
			)
			(layer "B.Fab")
		)
		(fp_line
			(start 0.12065 0.2794)
			(end 0.12065 0.3048)
			(stroke
				(width 0.1)
				(type default)
			)
			(layer "B.Fab")
		)
		(fp_line
			(start -0.12065 -0.2794)
			(end -0.12065 -0.3048)
			(stroke
				(width 0.1)
				(type default)
			)
			(layer "B.Fab")
		)
		(fp_line
			(start 0.12065 -0.2794)
			(end -0.12065 -0.2794)
			(stroke
				(width 0.1)
				(type default)
			)
			(layer "B.Fab")
		)
		(fp_line
			(start -0.67945 -0.3048)
			(end -0.67945 0.3048)
			(stroke
				(width 0.1)
				(type default)
			)
			(layer "B.Fab")
		)
		(fp_line
			(start -0.12065 -0.3048)
			(end -0.67945 -0.3048)
			(stroke
				(width 0.1)
				(type default)
			)
			(layer "B.Fab")
		)
		(fp_line
			(start 0.12065 -0.305054)
			(end 0.12065 -0.2794)
			(stroke
				(width 0.1)
				(type default)
			)
			(layer "B.Fab")
		)
		(fp_line
			(start 0.67945 -0.305054)
			(end 0.12065 -0.305054)
			(stroke
				(width 0.1)
				(type default)
			)
			(layer "B.Fab")
		)
		(pad "1" smd circle
			(at 0.40005 0 90)
			(size 0 0)
			(layers "B.Cu" "B.Mask" "B.Paste")
			(net "FM_JTAG_TCK_MUX_BMC_SEL")
		)
		(pad "2" smd circle
			(at -0.40005 0 90)
			(size 0 0)
			(layers "B.Cu" "B.Mask" "B.Paste")
			(net "FM_JTAG_TCK_MUX_BMC_SEL_R1")
		)
	)
)
